(kicad_pcb
	(version 20241229)
	(generator "pcbnew")
	(generator_version "9.0")
	(general
		(thickness 1.61)
		(legacy_teardrops no)
	)
	(paper "A3")
	(title_block
		(title "SO-DIMM DDR5 Tester")
		(date "2025-11-26")
		(rev "1.3.0")
		(comment 9 "footprints 587-593 of 627")
	)
	(layers
		(0 "F.Cu" signal)
		(4 "In1.Cu" power)
		(6 "In2.Cu" mixed)
		(8 "In3.Cu" power)
		(10 "In4.Cu" mixed)
		(12 "In5.Cu" power)
		(14 "In6.Cu" mixed)
		(16 "In7.Cu" power)
		(18 "In8.Cu" power)
		(20 "In9.Cu" mixed)
		(22 "In10.Cu" power)
		(2 "B.Cu" signal)
		(9 "F.Adhes" user "F.Adhesive")
		(11 "B.Adhes" user "B.Adhesive")
		(13 "F.Paste" user)
		(15 "B.Paste" user)
		(5 "F.SilkS" user "F.Silkscreen")
		(7 "B.SilkS" user "B.Silkscreen")
		(1 "F.Mask" user)
		(3 "B.Mask" user)
		(17 "Dwgs.User" user "User.Drawings")
		(19 "Cmts.User" user "User.Comments")
		(21 "Eco1.User" user "User.Eco1")
		(23 "Eco2.User" user "User.Eco2")
		(25 "Edge.Cuts" user)
		(27 "Margin" user)
		(31 "F.CrtYd" user "F.Courtyard")
		(29 "B.CrtYd" user "B.Courtyard")
		(35 "F.Fab" user)
		(33 "B.Fab" user)
	)
	(footprint "antmicro-footprints:C_0402_1005Metric"
		(layer "B.Cu")
		(at 147.877001 178.3025 180)
		(descr "Capacitor SMD 0402 (1005 Metric), square (rectangular) end terminal, IPC_7351 nominal, (Body size source: IPC-SM-782 page 76, https://www.pcb-3d.com/wordpress/wp-content/uploads/ipc-sm-782a_amendment_1_and_2.pdf)")
		(tags "capacitor 0402")
		(property "Reference" "C98"
			(at 0 1.17 0)
			(layer "B.SilkS")
			(hide yes)
			(effects
				(font
					(size 0.7 0.7)
					(thickness 0.15)
				)
				(justify left bottom mirror)
			)
		)
		(property "Value" "C_100n_0402"
			(at 0 -1.169 0)
			(layer "B.Fab")
			(effects
				(font
					(size 0.7 0.7)
					(thickness 0.15)
				)
				(justify left bottom mirror)
			)
		)
		(property "Datasheet" "https://www.murata.com/products/productdetail?partno=GRM155R61H104KE14%23"
			(at 0 0 180)
			(layer "F.Fab")
			(hide yes)
			(effects
				(font
					(size 1.27 1.27)
					(thickness 0.15)
				)
			)
		)
		(property "Author" "Antmicro"
			(at 295.754002 356.605 0)
			(layer "B.Fab")
			(hide yes)
			(effects
				(font
					(size 1 1)
					(thickness 0.15)
				)
				(justify mirror)
			)
		)
		(property "Dielectric" "X5R"
			(at 295.754002 356.605 0)
			(layer "B.Fab")
			(hide yes)
			(effects
				(font
					(size 1 1)
					(thickness 0.15)
				)
				(justify mirror)
			)
		)
		(property "License" "Apache-2.0"
			(at 295.754002 356.605 0)
			(layer "B.Fab")
			(hide yes)
			(effects
				(font
					(size 1 1)
					(thickness 0.15)
				)
				(justify mirror)
			)
		)
		(property "MPN" "GRM155R61H104KE14D"
			(at 295.754002 356.605 0)
			(layer "B.Fab")
			(hide yes)
			(effects
				(font
					(size 1 1)
					(thickness 0.15)
				)
				(justify mirror)
			)
		)
		(property "Manufacturer" "Murata"
			(at 295.754002 356.605 0)
			(layer "B.Fab")
			(hide yes)
			(effects
				(font
					(size 1 1)
					(thickness 0.15)
				)
				(justify mirror)
			)
		)
		(property "Val" "100n"
			(at 295.754002 356.605 0)
			(layer "B.Fab")
			(hide yes)
			(effects
				(font
					(size 1 1)
					(thickness 0.15)
				)
				(justify mirror)
			)
		)
		(property "Voltage" "50V"
			(at 295.754002 356.605 0)
			(layer "B.Fab")
			(hide yes)
			(effects
				(font
					(size 1 1)
					(thickness 0.15)
				)
				(justify mirror)
			)
		)
		(sheetname "/FPGA power/")
		(sheetfile "fpga-power.kicad_sch")
		(attr smd)
		(fp_rect
			(start -0.9656 0.4572)
			(end 0.9652 -0.4828)
			(stroke
				(width 0.05)
				(type solid)
			)
			(fill no)
			(layer "B.CrtYd")
		)
		(fp_line
			(start 0.498 0.25)
			(end 0.498 -0.248)
			(stroke
				(width 0.15)
				(type solid)
			)
			(layer "B.Fab")
		)
		(fp_line
			(start 0.498 -0.248)
			(end -0.5 -0.248)
			(stroke
				(width 0.15)
				(type solid)
			)
			(layer "B.Fab")
		)
		(fp_line
			(start -0.5 0.25)
			(end 0.498 0.25)
			(stroke
				(width 0.15)
				(type solid)
			)
			(layer "B.Fab")
		)
		(fp_line
			(start -0.5 -0.248)
			(end -0.5 0.25)
			(stroke
				(width 0.15)
				(type solid)
			)
			(layer "B.Fab")
		)
		(pad "1" smd roundrect
			(at -0.5 0 90)
			(size 0.6 0.6)
			(layers "B.Cu" "B.Mask" "B.Paste")
			(roundrect_rratio 0.25)
			(net 1 "GND")
			(pintype "passive")
		)
		(pad "2" smd roundrect
			(at 0.498 0 180)
			(size 0.6 0.6)
			(layers "B.Cu" "B.Mask" "B.Paste")
			(roundrect_rratio 0.25)
			(net 187 "+1V0_MGTAVCC")
			(pintype "passive")
		)
	)
	(footprint "antmicro-footprints:C_0402_1005Metric"
		(layer "B.Cu")
		(at 141.875501 169.301)
		(descr "Capacitor SMD 0402 (1005 Metric), square (rectangular) end terminal, IPC_7351 nominal, (Body size source: IPC-SM-782 page 76, https://www.pcb-3d.com/wordpress/wp-content/uploads/ipc-sm-782a_amendment_1_and_2.pdf)")
		(tags "capacitor 0402")
		(property "Reference" "C78"
			(at 0 1.17 180)
			(layer "B.SilkS")
			(hide yes)
			(effects
				(font
					(size 0.7 0.7)
					(thickness 0.15)
				)
				(justify left bottom mirror)
			)
		)
		(property "Value" "C_100n_0402"
			(at 0 -1.169 180)
			(layer "B.Fab")
			(effects
				(font
					(size 0.7 0.7)
					(thickness 0.15)
				)
				(justify left bottom mirror)
			)
		)
		(property "Datasheet" "https://www.murata.com/products/productdetail?partno=GRM155R61H104KE14%23"
			(at 0 0 0)
			(layer "F.Fab")
			(hide yes)
			(effects
				(font
					(size 1.27 1.27)
					(thickness 0.15)
				)
			)
		)
		(property "Author" "Antmicro"
			(at 0 0 0)
			(layer "B.Fab")
			(hide yes)
			(effects
				(font
					(size 1 1)
					(thickness 0.15)
				)
				(justify mirror)
			)
		)
		(property "Dielectric" "X5R"
			(at 0 0 0)
			(layer "B.Fab")
			(hide yes)
			(effects
				(font
					(size 1 1)
					(thickness 0.15)
				)
				(justify mirror)
			)
		)
		(property "License" "Apache-2.0"
			(at 0 0 0)
			(layer "B.Fab")
			(hide yes)
			(effects
				(font
					(size 1 1)
					(thickness 0.15)
				)
				(justify mirror)
			)
		)
		(property "MPN" "GRM155R61H104KE14D"
			(at 0 0 0)
			(layer "B.Fab")
			(hide yes)
			(effects
				(font
					(size 1 1)
					(thickness 0.15)
				)
				(justify mirror)
			)
		)
		(property "Manufacturer" "Murata"
			(at 0 0 0)
			(layer "B.Fab")
			(hide yes)
			(effects
				(font
					(size 1 1)
					(thickness 0.15)
				)
				(justify mirror)
			)
		)
		(property "Val" "100n"
			(at 0 0 0)
			(layer "B.Fab")
			(hide yes)
			(effects
				(font
					(size 1 1)
					(thickness 0.15)
				)
				(justify mirror)
			)
		)
		(property "Voltage" "50V"
			(at 0 0 0)
			(layer "B.Fab")
			(hide yes)
			(effects
				(font
					(size 1 1)
					(thickness 0.15)
				)
				(justify mirror)
			)
		)
		(sheetname "/FPGA power/")
		(sheetfile "fpga-power.kicad_sch")
		(attr smd)
		(fp_rect
			(start -0.9656 0.4572)
			(end 0.9652 -0.4828)
			(stroke
				(width 0.05)
				(type solid)
			)
			(fill no)
			(layer "B.CrtYd")
		)
		(fp_line
			(start -0.5 -0.248)
			(end -0.5 0.25)
			(stroke
				(width 0.15)
				(type solid)
			)
			(layer "B.Fab")
		)
		(fp_line
			(start -0.5 0.25)
			(end 0.498 0.25)
			(stroke
				(width 0.15)
				(type solid)
			)
			(layer "B.Fab")
		)
		(fp_line
			(start 0.498 -0.248)
			(end -0.5 -0.248)
			(stroke
				(width 0.15)
				(type solid)
			)
			(layer "B.Fab")
		)
		(fp_line
			(start 0.498 0.25)
			(end 0.498 -0.248)
			(stroke
				(width 0.15)
				(type solid)
			)
			(layer "B.Fab")
		)
		(pad "1" smd roundrect
			(at -0.5 0 270)
			(size 0.6 0.6)
			(layers "B.Cu" "B.Mask" "B.Paste")
			(roundrect_rratio 0.25)
			(net 1 "GND")
			(pintype "passive")
		)
		(pad "2" smd roundrect
			(at 0.498 0)
			(size 0.6 0.6)
			(layers "B.Cu" "B.Mask" "B.Paste")
			(roundrect_rratio 0.25)
			(net 206 "+1V1")
			(pintype "passive")
		)
	)
	(footprint "antmicro-footprints:Fiducial_1mm_Mask2mm"
		(layer "B.Cu")
		(at 82.460501 197.866 180)
		(descr "Circular Fiducial, 1mm bare copper, 3mm soldermask opening")
		(tags "fiducial")
		(property "Reference" "FID1001"
			(at 0 1.4 0)
			(layer "B.SilkS")
			(hide yes)
			(effects
				(font
					(size 0.7 0.7)
					(thickness 0.15)
				)
				(justify left bottom mirror)
			)
		)
		(property "Value" "Fiducial_1mm_Mask2mm"
			(at 0 -2.2 0)
			(layer "B.Fab")
			(effects
				(font
					(size 0.7 0.7)
					(thickness 0.15)
				)
				(justify left bottom mirror)
			)
		)
		(property "Author" "Antmicro"
			(at 164.921002 395.732 0)
			(layer "B.Fab")
			(hide yes)
			(effects
				(font
					(size 1 1)
					(thickness 0.15)
				)
				(justify mirror)
			)
		)
		(property "License" "Apache-2.0"
			(at 164.921002 395.732 0)
			(layer "B.Fab")
			(hide yes)
			(effects
				(font
					(size 1 1)
					(thickness 0.15)
				)
				(justify mirror)
			)
		)
		(property "MPN" ""
			(at 164.921002 395.732 0)
			(layer "B.Fab")
			(hide yes)
			(effects
				(font
					(size 1 1)
					(thickness 0.15)
				)
				(justify mirror)
			)
		)
		(property "Manufacturer" ""
			(at 164.921002 395.732 0)
			(layer "B.Fab")
			(hide yes)
			(effects
				(font
					(size 1 1)
					(thickness 0.15)
				)
				(justify mirror)
			)
		)
		(sheetfile "sodimm-ddr5-tester.kicad_sch")
		(attr board_only exclude_from_pos_files exclude_from_bom)
		(fp_circle
			(center 0 0)
			(end 1.24 0)
			(stroke
				(width 0.05)
				(type solid)
			)
			(fill no)
			(layer "B.CrtYd")
		)
		(fp_circle
			(center 0 0)
			(end 0.999 0)
			(stroke
				(width 0.15)
				(type solid)
			)
			(fill no)
			(layer "B.Fab")
		)
		(pad "" smd circle
			(at 0 0 180)
			(size 1 1)
			(layers "B.Cu" "B.Mask")
			(solder_mask_margin 0.5)
			(clearance 0.5)
		)
	)
	(footprint "antmicro-footprints:R_0402_1005Metric"
		(layer "B.Cu")
		(at 180.8 193 180)
		(descr "Resistor SMD 0402")
		(tags "resistor SMD 0402")
		(property "Reference" "R178"
			(at 1.25 -0.4 0)
			(layer "B.SilkS")
			(effects
				(font
					(size 0.7 0.7)
					(thickness 0.15)
				)
				(justify left bottom mirror)
			)
		)
		(property "Value" "R_0R_0402"
			(at -1.011843 -1.772047 0)
			(layer "B.Fab")
			(effects
				(font
					(size 0.7 0.7)
					(thickness 0.15)
				)
				(justify left bottom mirror)
			)
		)
		(property "Datasheet" "https://industrial.panasonic.com/cdbs/www-data/pdf/RDA0000/AOA0000C301.pdf"
			(at 0 0 180)
			(layer "F.Fab")
			(hide yes)
			(effects
				(font
					(size 1.27 1.27)
					(thickness 0.15)
				)
			)
		)
		(property "Author" "Antmicro"
			(at 361.6 386 0)
			(layer "B.Fab")
			(hide yes)
			(effects
				(font
					(size 1 1)
					(thickness 0.15)
				)
				(justify mirror)
			)
		)
		(property "Current" "1A"
			(at 361.6 386 0)
			(layer "B.Fab")
			(hide yes)
			(effects
				(font
					(size 1 1)
					(thickness 0.15)
				)
				(justify mirror)
			)
		)
		(property "License" "Apache-2.0"
			(at 361.6 386 0)
			(layer "B.Fab")
			(hide yes)
			(effects
				(font
					(size 1 1)
					(thickness 0.15)
				)
				(justify mirror)
			)
		)
		(property "MPN" "ERJ2GE0R00X"
			(at 361.6 386 0)
			(layer "B.Fab")
			(hide yes)
			(effects
				(font
					(size 1 1)
					(thickness 0.15)
				)
				(justify mirror)
			)
		)
		(property "Manufacturer" "Panasonic"
			(at 361.6 386 0)
			(layer "B.Fab")
			(hide yes)
			(effects
				(font
					(size 1 1)
					(thickness 0.15)
				)
				(justify mirror)
			)
		)
		(property "Tolerance" ""
			(at 361.6 386 0)
			(layer "B.Fab")
			(hide yes)
			(effects
				(font
					(size 1 1)
					(thickness 0.15)
				)
				(justify mirror)
			)
		)
		(property "Val" "0R"
			(at 361.6 386 0)
			(layer "B.Fab")
			(hide yes)
			(effects
				(font
					(size 1 1)
					(thickness 0.15)
				)
				(justify mirror)
			)
		)
		(sheetname "/I^{2}C/")
		(sheetfile "i2c.kicad_sch")
		(attr exclude_from_pos_files exclude_from_bom dnp)
		(fp_rect
			(start -0.93 0.47)
			(end 0.93 -0.47)
			(stroke
				(width 0.05)
				(type solid)
			)
			(fill no)
			(layer "B.CrtYd")
		)
		(fp_rect
			(start -0.5 0.25)
			(end 0.5 -0.25)
			(stroke
				(width 0.15)
				(type solid)
			)
			(fill no)
			(layer "B.Fab")
		)
		(pad "1" smd roundrect
			(at -0.485 0 180)
			(size 0.59 0.64)
			(layers "B.Cu" "B.Mask" "B.Paste")
			(roundrect_rratio 0.25)
			(net 691 "/I^{2}C/PWR.SCL")
			(pintype "passive")
		)
		(pad "2" smd roundrect
			(at 0.485 0 180)
			(size 0.59 0.64)
			(layers "B.Cu" "B.Mask" "B.Paste")
			(roundrect_rratio 0.25)
			(net 689 "/FPGA bank 14/FPGA_PWR.SCL")
			(pintype "passive")
		)
	)
	(footprint "antmicro-footprints:R_0402_1005Metric"
		(layer "B.Cu")
		(at 196.7 189.175)
		(descr "Resistor SMD 0402")
		(tags "resistor SMD 0402")
		(property "Reference" "R152"
			(at 1.33 1.385 180)
			(layer "B.SilkS")
			(effects
				(font
					(size 0.7 0.7)
					(thickness 0.15)
				)
				(justify left bottom mirror)
			)
		)
		(property "Value" "R_0R_0402"
			(at -1.011843 -1.772047 180)
			(layer "B.Fab")
			(effects
				(font
					(size 0.7 0.7)
					(thickness 0.15)
				)
				(justify left bottom mirror)
			)
		)
		(property "Datasheet" "https://industrial.panasonic.com/cdbs/www-data/pdf/RDA0000/AOA0000C301.pdf"
			(at 0 0 0)
			(layer "F.Fab")
			(hide yes)
			(effects
				(font
					(size 1.27 1.27)
					(thickness 0.15)
				)
			)
		)
		(property "Author" "Antmicro"
			(at 0 0 0)
			(layer "B.Fab")
			(hide yes)
			(effects
				(font
					(size 1 1)
					(thickness 0.15)
				)
				(justify mirror)
			)
		)
		(property "Current" "1A"
			(at 0 0 0)
			(layer "B.Fab")
			(hide yes)
			(effects
				(font
					(size 1 1)
					(thickness 0.15)
				)
				(justify mirror)
			)
		)
		(property "License" "Apache-2.0"
			(at 0 0 0)
			(layer "B.Fab")
			(hide yes)
			(effects
				(font
					(size 1 1)
					(thickness 0.15)
				)
				(justify mirror)
			)
		)
		(property "MPN" "ERJ2GE0R00X"
			(at 0 0 0)
			(layer "B.Fab")
			(hide yes)
			(effects
				(font
					(size 1 1)
					(thickness 0.15)
				)
				(justify mirror)
			)
		)
		(property "Manufacturer" "Panasonic"
			(at 0 0 0)
			(layer "B.Fab")
			(hide yes)
			(effects
				(font
					(size 1 1)
					(thickness 0.15)
				)
				(justify mirror)
			)
		)
		(property "Tolerance" ""
			(at 0 0 0)
			(layer "B.Fab")
			(hide yes)
			(effects
				(font
					(size 1 1)
					(thickness 0.15)
				)
				(justify mirror)
			)
		)
		(property "Val" "0R"
			(at 0 0 0)
			(layer "B.Fab")
			(hide yes)
			(effects
				(font
					(size 1 1)
					(thickness 0.15)
				)
				(justify mirror)
			)
		)
		(sheetname "/Supply/")
		(sheetfile "supply.kicad_sch")
		(attr exclude_from_pos_files exclude_from_bom dnp)
		(fp_rect
			(start -0.93 0.47)
			(end 0.93 -0.47)
			(stroke
				(width 0.05)
				(type solid)
			)
			(fill no)
			(layer "B.CrtYd")
		)
		(fp_rect
			(start -0.5 0.25)
			(end 0.5 -0.25)
			(stroke
				(width 0.15)
				(type solid)
			)
			(fill no)
			(layer "B.Fab")
		)
		(pad "1" smd roundrect
			(at -0.485 0)
			(size 0.59 0.64)
			(layers "B.Cu" "B.Mask" "B.Paste")
			(roundrect_rratio 0.25)
			(net 1 "GND")
			(pintype "passive")
		)
		(pad "2" smd roundrect
			(at 0.485 0)
			(size 0.59 0.64)
			(layers "B.Cu" "B.Mask" "B.Paste")
			(roundrect_rratio 0.25)
			(net 210 "/Supply/FB1")
			(pintype "passive")
		)
	)
	(footprint "antmicro-footprints:R_0402_1005Metric"
		(layer "B.Cu")
		(at 137.777001 160.8005 180)
		(descr "Resistor SMD 0402")
		(tags "resistor SMD 0402")
		(property "Reference" "R129"
			(at -1.122484 0.772697 0)
			(layer "B.SilkS")
			(hide yes)
			(effects
				(font
					(size 0.7 0.7)
					(thickness 0.15)
				)
				(justify left bottom mirror)
			)
		)
		(property "Value" "R_1k_0402"
			(at -1.011843 -1.772047 0)
			(layer "B.Fab")
			(effects
				(font
					(size 0.7 0.7)
					(thickness 0.15)
				)
				(justify left bottom mirror)
			)
		)
		(property "Datasheet" "https://www.bourns.com/docs/product-datasheets/cr.pdf"
			(at 0 0 180)
			(layer "F.Fab")
			(hide yes)
			(effects
				(font
					(size 1.27 1.27)
					(thickness 0.15)
				)
			)
		)
		(property "Author" "Antmicro"
			(at 275.554002 321.601 0)
			(layer "B.Fab")
			(hide yes)
			(effects
				(font
					(size 1 1)
					(thickness 0.15)
				)
				(justify mirror)
			)
		)
		(property "License" "Apache-2.0"
			(at 275.554002 321.601 0)
			(layer "B.Fab")
			(hide yes)
			(effects
				(font
					(size 1 1)
					(thickness 0.15)
				)
				(justify mirror)
			)
		)
		(property "MPN" "CR0402-FX-1001GLF"
			(at 275.554002 321.601 0)
			(layer "B.Fab")
			(hide yes)
			(effects
				(font
					(size 1 1)
					(thickness 0.15)
				)
				(justify mirror)
			)
		)
		(property "Manufacturer" "Bourns"
			(at 275.554002 321.601 0)
			(layer "B.Fab")
			(hide yes)
			(effects
				(font
					(size 1 1)
					(thickness 0.15)
				)
				(justify mirror)
			)
		)
		(property "Tolerance" "1%"
			(at 275.554002 321.601 0)
			(layer "B.Fab")
			(hide yes)
			(effects
				(font
					(size 1 1)
					(thickness 0.15)
				)
				(justify mirror)
			)
		)
		(property "Val" "1k"
			(at 275.554002 321.601 0)
			(layer "B.Fab")
			(hide yes)
			(effects
				(font
					(size 1 1)
					(thickness 0.15)
				)
				(justify mirror)
			)
		)
		(sheetname "/FPGA banks HP/")
		(sheetfile "fpga-banks-32-34.kicad_sch")
		(attr smd)
		(fp_rect
			(start -0.93 0.47)
			(end 0.93 -0.47)
			(stroke
				(width 0.05)
				(type solid)
			)
			(fill no)
			(layer "B.CrtYd")
		)
		(fp_rect
			(start -0.5 0.25)
			(end 0.5 -0.25)
			(stroke
				(width 0.15)
				(type solid)
			)
			(fill no)
			(layer "B.Fab")
		)
		(pad "1" smd roundrect
			(at -0.485 0 180)
			(size 0.59 0.64)
			(layers "B.Cu" "B.Mask" "B.Paste")
			(roundrect_rratio 0.25)
			(net 379 "Net-(R129-Pad1)")
			(pintype "passive")
		)
		(pad "2" smd roundrect
			(at 0.485 0 180)
			(size 0.59 0.64)
			(layers "B.Cu" "B.Mask" "B.Paste")
			(roundrect_rratio 0.25)
			(net 206 "+1V1")
			(pintype "passive")
		)
	)
	(footprint "antmicro-footprints:R_0402_1005Metric"
		(layer "B.Cu")
		(at 122.350501 176.476 180)
		(descr "Resistor SMD 0402")
		(tags "resistor SMD 0402")
		(property "Reference" "R1"
			(at -1.122484 0.772697 0)
			(layer "B.SilkS")
			(hide yes)
			(effects
				(font
					(size 0.7 0.7)
					(thickness 0.15)
				)
				(justify left bottom mirror)
			)
		)
		(property "Value" "R_10k_0402"
			(at -1.011843 -1.772047 0)
			(layer "B.Fab")
			(effects
				(font
					(size 0.7 0.7)
					(thickness 0.15)
				)
				(justify left bottom mirror)
			)
		)
		(property "Datasheet" "https://www.bourns.com/docs/product-datasheets/cr.pdf"
			(at 0 0 180)
			(layer "F.Fab")
			(hide yes)
			(effects
				(font
					(size 1.27 1.27)
					(thickness 0.15)
				)
			)
		)
		(property "Author" "Antmicro"
			(at 244.701002 352.952 0)
			(layer "B.Fab")
			(hide yes)
			(effects
				(font
					(size 1 1)
					(thickness 0.15)
				)
				(justify mirror)
			)
		)
		(property "License" "Apache-2.0"
			(at 244.701002 352.952 0)
			(layer "B.Fab")
			(hide yes)
			(effects
				(font
					(size 1 1)
					(thickness 0.15)
				)
				(justify mirror)
			)
		)
		(property "MPN" "CR0402-FX-1002GLF"
			(at 244.701002 352.952 0)
			(layer "B.Fab")
			(hide yes)
			(effects
				(font
					(size 1 1)
					(thickness 0.15)
				)
				(justify mirror)
			)
		)
		(property "Manufacturer" "Bourns"
			(at 244.701002 352.952 0)
			(layer "B.Fab")
			(hide yes)
			(effects
				(font
					(size 1 1)
					(thickness 0.15)
				)
				(justify mirror)
			)
		)
		(property "Tolerance" "1%"
			(at 244.701002 352.952 0)
			(layer "B.Fab")
			(hide yes)
			(effects
				(font
					(size 1 1)
					(thickness 0.15)
				)
				(justify mirror)
			)
		)
		(property "Val" "10k"
			(at 244.701002 352.952 0)
			(layer "B.Fab")
			(hide yes)
			(effects
				(font
					(size 1 1)
					(thickness 0.15)
				)
				(justify mirror)
			)
		)
		(sheetname "/HyperRAM + QSPI Flash/")
		(sheetfile "hyperram-flash.kicad_sch")
		(attr smd)
		(fp_rect
			(start -0.93 0.47)
			(end 0.93 -0.47)
			(stroke
				(width 0.05)
				(type solid)
			)
			(fill no)
			(layer "B.CrtYd")
		)
		(fp_rect
			(start -0.5 0.25)
			(end 0.5 -0.25)
			(stroke
				(width 0.15)
				(type solid)
			)
			(fill no)
			(layer "B.Fab")
		)
		(pad "1" smd roundrect
			(at -0.485 0 180)
			(size 0.59 0.64)
			(layers "B.Cu" "B.Mask" "B.Paste")
			(roundrect_rratio 0.25)
			(net 200 "+3V3")
			(pintype "passive")
		)
		(pad "2" smd roundrect
			(at 0.485 0 180)
			(size 0.59 0.64)
			(layers "B.Cu" "B.Mask" "B.Paste")
			(roundrect_rratio 0.25)
			(net 623 "/FPGA bank 12/HyperRAM.~{RESET}")
			(pintype "passive")
		)
	)
)
